(kicad_pcb
	(version 20260206)
	(generator "pcbnew")
	(generator_version "10.0")
	(general
		(thickness 1.6)
		(legacy_teardrops no)
	)
	(paper "A4")
	(title_block
		(title "04192023_DAF0TMB3IC0_F0TG_MB_C_brd_V02_OCP.brd")
		(comment 1 "Grand Teton / footprints 4886-4889 of 8354")
	)
	(layers
		(0 "F.Cu" signal "TOP")
		(4 "In1.Cu" signal "GND")
		(6 "In2.Cu" signal "IN1")
		(8 "In3.Cu" signal "GND1")
		(10 "In4.Cu" signal "IN2")
		(12 "In5.Cu" signal "GND2")
		(14 "In6.Cu" signal "IN3")
		(16 "In7.Cu" signal "GND3")
		(18 "In8.Cu" signal "VCC")
		(20 "In9.Cu" signal "VCC1")
		(22 "In10.Cu" signal "GND4")
		(24 "In11.Cu" signal "IN4")
		(26 "In12.Cu" signal "GND5")
		(28 "In13.Cu" signal "IN5")
		(30 "In14.Cu" signal "GND6")
		(32 "In15.Cu" signal "IN6")
		(34 "In16.Cu" signal "GND7")
		(2 "B.Cu" signal "BOTTOM")
		(9 "F.Adhes" user "F.Adhesive")
		(11 "B.Adhes" user "B.Adhesive")
		(13 "F.Paste" user "Package Geometry/Pastemask Top")
		(15 "B.Paste" user "Package Geometry/Pastemask Bottom")
		(5 "F.SilkS" user "Ref Des/Silkscreen Top")
		(7 "B.SilkS" user "Ref Des/Silkscreen Bottom")
		(1 "F.Mask" user "Board Geometry/Soldermask Top")
		(3 "B.Mask" user "Board Geometry/Soldermask Bottom")
		(17 "Dwgs.User" user "User.Drawings")
		(19 "Cmts.User" user "User.Comments")
		(21 "Eco1.User" user "User.Eco1")
		(23 "Eco2.User" user "User.Eco2")
		(25 "Edge.Cuts" user "Board Geometry/Outline")
		(27 "Margin" user)
		(31 "F.CrtYd" user "Package Geometry/Place Bound Top")
		(29 "B.CrtYd" user "Package Geometry/Place Bound Bottom")
		(35 "F.Fab" user "Ref Des/Assembly Top")
		(33 "B.Fab" user "Ref Des/Assembly Bottom")
	)
	(footprint ""
		(layer "F.Cu")
		(at 39.842694 -423.21734)
		(property "Reference" "R6155"
			(at 0 0 0)
			(layer "F.SilkS")
			(hide yes)
			(effects
				(font
					(size 1.27 1.27)
				)
			)
		)
		(property "Value" ""
			(at 0 0 0)
			(layer "F.Fab")
			(effects
				(font
					(size 1.27 1.27)
				)
			)
		)
		(duplicate_pad_numbers_are_jumpers no)
		(fp_line
			(start -0.32512 -0.175006)
			(end 0.32512 -0.175006)
			(stroke
				(width 0.1)
				(type default)
			)
			(layer "F.Fab")
		)
		(fp_line
			(start -0.32512 0.175006)
			(end -0.32512 -0.175006)
			(stroke
				(width 0.1)
				(type default)
			)
			(layer "F.Fab")
		)
		(fp_line
			(start 0.32512 -0.175006)
			(end 0.32512 0.175006)
			(stroke
				(width 0.1)
				(type default)
			)
			(layer "F.Fab")
		)
		(fp_line
			(start 0.32512 0.175006)
			(end -0.32512 0.175006)
			(stroke
				(width 0.1)
				(type default)
			)
			(layer "F.Fab")
		)
		(pad "1" smd rect
			(at -0.2667 0)
			(size 0.3048 0.381)
			(layers "F.Cu" "F.Mask" "F.Paste")
			(net "P2E_MB_BMC_TX_C_DN<0>")
		)
		(pad "2" smd rect
			(at 0.2667 0 180)
			(size 0.3048 0.381)
			(layers "F.Cu" "F.Mask" "F.Paste")
			(net "P2E_MB_BMC_TX_C_R2_DN<0>")
		)
	)
	(footprint ""
		(layer "F.Cu")
		(at 222.738442 -315.95568 90)
		(property "Reference" "PC6533"
			(at 0 0 90)
			(layer "F.SilkS")
			(hide yes)
			(effects
				(font
					(size 1.27 1.27)
				)
			)
		)
		(property "Value" ""
			(at 0 0 90)
			(layer "F.Fab")
			(effects
				(font
					(size 1.27 1.27)
				)
			)
		)
		(duplicate_pad_numbers_are_jumpers no)
		(fp_line
			(start 0.7874 -0.4064)
			(end 0.7874 0.4064)
			(stroke
				(width 0.1524)
				(type default)
			)
			(layer "F.SilkS")
		)
		(fp_line
			(start -0.7874 -0.4064)
			(end 0.7874 -0.4064)
			(stroke
				(width 0.1524)
				(type default)
			)
			(layer "F.SilkS")
		)
		(fp_line
			(start 0.7874 0.4064)
			(end -0.7874 0.4064)
			(stroke
				(width 0.1524)
				(type default)
			)
			(layer "F.SilkS")
		)
		(fp_line
			(start -0.7874 0.4064)
			(end -0.7874 -0.4064)
			(stroke
				(width 0.1524)
				(type default)
			)
			(layer "F.SilkS")
		)
		(fp_line
			(start -0.12065 -0.305054)
			(end -0.12065 -0.2794)
			(stroke
				(width 0.1)
				(type default)
			)
			(layer "F.Fab")
		)
		(fp_line
			(start -0.67945 -0.305054)
			(end -0.12065 -0.305054)
			(stroke
				(width 0.1)
				(type default)
			)
			(layer "F.Fab")
		)
		(fp_line
			(start 0.67945 -0.3048)
			(end 0.67945 0.3048)
			(stroke
				(width 0.1)
				(type default)
			)
			(layer "F.Fab")
		)
		(fp_line
			(start 0.12065 -0.3048)
			(end 0.67945 -0.3048)
			(stroke
				(width 0.1)
				(type default)
			)
			(layer "F.Fab")
		)
		(fp_line
			(start 0.12065 -0.2794)
			(end 0.12065 -0.3048)
			(stroke
				(width 0.1)
				(type default)
			)
			(layer "F.Fab")
		)
		(fp_line
			(start -0.12065 -0.2794)
			(end 0.12065 -0.2794)
			(stroke
				(width 0.1)
				(type default)
			)
			(layer "F.Fab")
		)
		(fp_line
			(start 0.120396 0.2794)
			(end -0.12065 0.2794)
			(stroke
				(width 0.1)
				(type default)
			)
			(layer "F.Fab")
		)
		(fp_line
			(start -0.12065 0.2794)
			(end -0.12065 0.3048)
			(stroke
				(width 0.1)
				(type default)
			)
			(layer "F.Fab")
		)
		(fp_line
			(start 0.67945 0.3048)
			(end 0.120396 0.3048)
			(stroke
				(width 0.1)
				(type default)
			)
			(layer "F.Fab")
		)
		(fp_line
			(start 0.120396 0.3048)
			(end 0.120396 0.2794)
			(stroke
				(width 0.1)
				(type default)
			)
			(layer "F.Fab")
		)
		(fp_line
			(start -0.12065 0.3048)
			(end -0.67945 0.3048)
			(stroke
				(width 0.1)
				(type default)
			)
			(layer "F.Fab")
		)
		(fp_line
			(start -0.67945 0.3048)
			(end -0.67945 -0.305054)
			(stroke
				(width 0.1)
				(type default)
			)
			(layer "F.Fab")
		)
		(pad "1" smd circle
			(at -0.40005 0 90)
			(size 0 0)
			(layers "F.Cu" "F.Mask" "F.Paste")
			(net "P1V8_CPU1_RT_1D")
		)
		(pad "2" smd circle
			(at 0.40005 0 90)
			(size 0 0)
			(layers "F.Cu" "F.Mask" "F.Paste")
			(net "GND")
		)
	)
	(footprint ""
		(layer "F.Cu")
		(at 80.223106 -58.890154 180)
		(property "Reference" "R3570"
			(at 0 0 180)
			(layer "F.SilkS")
			(hide yes)
			(effects
				(font
					(size 1.27 1.27)
				)
			)
		)
		(property "Value" ""
			(at 0 0 180)
			(layer "F.Fab")
			(effects
				(font
					(size 1.27 1.27)
				)
			)
		)
		(duplicate_pad_numbers_are_jumpers no)
		(fp_line
			(start 0.7874 0.4064)
			(end -0.7874 0.4064)
			(stroke
				(width 0.1524)
				(type default)
			)
			(layer "F.SilkS")
		)
		(fp_line
			(start 0.7874 -0.4064)
			(end 0.7874 0.4064)
			(stroke
				(width 0.1524)
				(type default)
			)
			(layer "F.SilkS")
		)
		(fp_line
			(start -0.7874 0.4064)
			(end -0.7874 -0.4064)
			(stroke
				(width 0.1524)
				(type default)
			)
			(layer "F.SilkS")
		)
		(fp_line
			(start -0.7874 -0.4064)
			(end 0.7874 -0.4064)
			(stroke
				(width 0.1524)
				(type default)
			)
			(layer "F.SilkS")
		)
		(fp_line
			(start 0.67945 0.3048)
			(end 0.120396 0.3048)
			(stroke
				(width 0.1)
				(type default)
			)
			(layer "F.Fab")
		)
		(fp_line
			(start 0.67945 -0.3048)
			(end 0.67945 0.3048)
			(stroke
				(width 0.1)
				(type default)
			)
			(layer "F.Fab")
		)
		(fp_line
			(start 0.12065 -0.2794)
			(end 0.12065 -0.3048)
			(stroke
				(width 0.1)
				(type default)
			)
			(layer "F.Fab")
		)
		(fp_line
			(start 0.12065 -0.3048)
			(end 0.67945 -0.3048)
			(stroke
				(width 0.1)
				(type default)
			)
			(layer "F.Fab")
		)
		(fp_line
			(start 0.120396 0.3048)
			(end 0.120396 0.2794)
			(stroke
				(width 0.1)
				(type default)
			)
			(layer "F.Fab")
		)
		(fp_line
			(start 0.120396 0.2794)
			(end -0.12065 0.2794)
			(stroke
				(width 0.1)
				(type default)
			)
			(layer "F.Fab")
		)
		(fp_line
			(start -0.12065 0.3048)
			(end -0.67945 0.3048)
			(stroke
				(width 0.1)
				(type default)
			)
			(layer "F.Fab")
		)
		(fp_line
			(start -0.12065 0.2794)
			(end -0.12065 0.3048)
			(stroke
				(width 0.1)
				(type default)
			)
			(layer "F.Fab")
		)
		(fp_line
			(start -0.12065 -0.2794)
			(end 0.12065 -0.2794)
			(stroke
				(width 0.1)
				(type default)
			)
			(layer "F.Fab")
		)
		(fp_line
			(start -0.12065 -0.305054)
			(end -0.12065 -0.2794)
			(stroke
				(width 0.1)
				(type default)
			)
			(layer "F.Fab")
		)
		(fp_line
			(start -0.67945 0.3048)
			(end -0.67945 -0.305054)
			(stroke
				(width 0.1)
				(type default)
			)
			(layer "F.Fab")
		)
		(fp_line
			(start -0.67945 -0.305054)
			(end -0.12065 -0.305054)
			(stroke
				(width 0.1)
				(type default)
			)
			(layer "F.Fab")
		)
		(pad "1" smd circle
			(at -0.40005 0 180)
			(size 0 0)
			(layers "F.Cu" "F.Mask" "F.Paste")
			(net "P3V3_OCP_V3_2_R")
		)
		(pad "2" smd circle
			(at 0.40005 0 180)
			(size 0 0)
			(layers "F.Cu" "F.Mask" "F.Paste")
			(net "VSENSE_P12V_INA230_3_INP")
		)
	)
	(footprint ""
		(layer "F.Cu")
		(at 160.817306 -408.517344 -90)
		(property "Reference" "C6724"
			(at 0 0 270)
			(layer "F.SilkS")
			(hide yes)
			(effects
				(font
					(size 1.27 1.27)
				)
			)
		)
		(property "Value" ""
			(at 0 0 270)
			(layer "F.Fab")
			(effects
				(font
					(size 1.27 1.27)
				)
			)
		)
		(duplicate_pad_numbers_are_jumpers no)
		(fp_line
			(start -0.299974 0.150114)
			(end -0.299974 -0.150114)
			(stroke
				(width 0.1)
				(type default)
			)
			(layer "F.Fab")
		)
		(fp_line
			(start 0.299974 0.150114)
			(end -0.299974 0.150114)
			(stroke
				(width 0.1)
				(type default)
			)
			(layer "F.Fab")
		)
		(fp_line
			(start -0.299974 -0.150114)
			(end 0.299974 -0.150114)
			(stroke
				(width 0.1)
				(type default)
			)
			(layer "F.Fab")
		)
		(fp_line
			(start 0.299974 -0.150114)
			(end 0.299974 0.150114)
			(stroke
				(width 0.1)
				(type default)
			)
			(layer "F.Fab")
		)
		(pad "1" smd rect
			(at -0.2667 0 270)
			(size 0.3048 0.381)
			(layers "F.Cu" "F.Mask" "F.Paste")
			(net "P5E_CPU1_P2_TX_BUF_C_DN<15>")
		)
		(pad "2" smd rect
			(at 0.2667 0 270)
			(size 0.3048 0.381)
			(layers "F.Cu" "F.Mask" "F.Paste")
			(net "P5E_CPU1_P2_TX_BUF_DN<15>")
		)
	)
)
